(kicad_pcb
	(version 20260206)
	(generator "pcbnew")
	(generator_version "10.0")
	(general
		(thickness 1.6)
		(legacy_teardrops no)
	)
	(paper "A4")
	(title_block
		(title "03242023_DA0F0TMBIJ0_F0T_Motherboard_J_brd_V01_OCP.brd")
		(comment 1 "Grand Teton / footprints 522-528 of 6105")
	)
	(layers
		(0 "F.Cu" signal "TOP")
		(4 "In1.Cu" signal "GND")
		(6 "In2.Cu" signal "IN1")
		(8 "In3.Cu" signal "GND1")
		(10 "In4.Cu" signal "IN2")
		(12 "In5.Cu" signal "GND2")
		(14 "In6.Cu" signal "IN3")
		(16 "In7.Cu" signal "GND3")
		(18 "In8.Cu" signal "VCC")
		(20 "In9.Cu" signal "VCC1")
		(22 "In10.Cu" signal "GND4")
		(24 "In11.Cu" signal "IN4")
		(26 "In12.Cu" signal "GND5")
		(28 "In13.Cu" signal "IN5")
		(30 "In14.Cu" signal "GND6")
		(32 "In15.Cu" signal "IN6")
		(34 "In16.Cu" signal "GND7")
		(2 "B.Cu" signal "BOTTOM")
		(9 "F.Adhes" user "F.Adhesive")
		(11 "B.Adhes" user "B.Adhesive")
		(13 "F.Paste" user "Package Geometry/Pastemask Top")
		(15 "B.Paste" user "Package Geometry/Pastemask Bottom")
		(5 "F.SilkS" user "Ref Des/Silkscreen Top")
		(7 "B.SilkS" user "Ref Des/Silkscreen Bottom")
		(1 "F.Mask" user "Board Geometry/Soldermask Top")
		(3 "B.Mask" user "Board Geometry/Soldermask Bottom")
		(17 "Dwgs.User" user "User.Drawings")
		(19 "Cmts.User" user "User.Comments")
		(21 "Eco1.User" user "User.Eco1")
		(23 "Eco2.User" user "User.Eco2")
		(25 "Edge.Cuts" user "Board Geometry/Outline")
		(27 "Margin" user)
		(31 "F.CrtYd" user "Package Geometry/Place Bound Top")
		(29 "B.CrtYd" user "Package Geometry/Place Bound Bottom")
		(35 "F.Fab" user "Ref Des/Assembly Top")
		(33 "B.Fab" user "Ref Des/Assembly Bottom")
	)
	(footprint ""
		(layer "F.Cu")
		(at 216.065608 -407.871422 180)
		(property "Reference" "PR3912"
			(at 0 0 180)
			(layer "F.SilkS")
			(hide yes)
			(effects
				(font
					(size 1.27 1.27)
				)
			)
		)
		(property "Value" ""
			(at 0 0 180)
			(layer "F.Fab")
			(effects
				(font
					(size 1.27 1.27)
				)
			)
		)
		(duplicate_pad_numbers_are_jumpers no)
		(fp_line
			(start 0.7874 0.4064)
			(end -0.7874 0.4064)
			(stroke
				(width 0.1524)
				(type default)
			)
			(layer "F.SilkS")
		)
		(fp_line
			(start 0.7874 -0.4064)
			(end 0.7874 0.4064)
			(stroke
				(width 0.1524)
				(type default)
			)
			(layer "F.SilkS")
		)
		(fp_line
			(start -0.7874 0.4064)
			(end -0.7874 -0.4064)
			(stroke
				(width 0.1524)
				(type default)
			)
			(layer "F.SilkS")
		)
		(fp_line
			(start -0.7874 -0.4064)
			(end 0.7874 -0.4064)
			(stroke
				(width 0.1524)
				(type default)
			)
			(layer "F.SilkS")
		)
		(fp_line
			(start 0.67945 0.3048)
			(end 0.120396 0.3048)
			(stroke
				(width 0.1)
				(type default)
			)
			(layer "F.Fab")
		)
		(fp_line
			(start 0.67945 -0.3048)
			(end 0.67945 0.3048)
			(stroke
				(width 0.1)
				(type default)
			)
			(layer "F.Fab")
		)
		(fp_line
			(start 0.12065 -0.2794)
			(end 0.12065 -0.3048)
			(stroke
				(width 0.1)
				(type default)
			)
			(layer "F.Fab")
		)
		(fp_line
			(start 0.12065 -0.3048)
			(end 0.67945 -0.3048)
			(stroke
				(width 0.1)
				(type default)
			)
			(layer "F.Fab")
		)
		(fp_line
			(start 0.120396 0.3048)
			(end 0.120396 0.2794)
			(stroke
				(width 0.1)
				(type default)
			)
			(layer "F.Fab")
		)
		(fp_line
			(start 0.120396 0.2794)
			(end -0.12065 0.2794)
			(stroke
				(width 0.1)
				(type default)
			)
			(layer "F.Fab")
		)
		(fp_line
			(start -0.12065 0.3048)
			(end -0.67945 0.3048)
			(stroke
				(width 0.1)
				(type default)
			)
			(layer "F.Fab")
		)
		(fp_line
			(start -0.12065 0.2794)
			(end -0.12065 0.3048)
			(stroke
				(width 0.1)
				(type default)
			)
			(layer "F.Fab")
		)
		(fp_line
			(start -0.12065 -0.2794)
			(end 0.12065 -0.2794)
			(stroke
				(width 0.1)
				(type default)
			)
			(layer "F.Fab")
		)
		(fp_line
			(start -0.12065 -0.305054)
			(end -0.12065 -0.2794)
			(stroke
				(width 0.1)
				(type default)
			)
			(layer "F.Fab")
		)
		(fp_line
			(start -0.67945 0.3048)
			(end -0.67945 -0.305054)
			(stroke
				(width 0.1)
				(type default)
			)
			(layer "F.Fab")
		)
		(fp_line
			(start -0.67945 -0.305054)
			(end -0.12065 -0.305054)
			(stroke
				(width 0.1)
				(type default)
			)
			(layer "F.Fab")
		)
		(pad "1" smd circle
			(at -0.40005 0 180)
			(size 0 0)
			(layers "F.Cu" "F.Mask" "F.Paste")
			(net "AGND_HSC")
		)
		(pad "2" smd circle
			(at 0.40005 0 180)
			(size 0 0)
			(layers "F.Cu" "F.Mask" "F.Paste")
			(net "HSC_MODE_2")
		)
	)
	(footprint ""
		(layer "F.Cu")
		(at 218.08948 -126.761748)
		(property "Reference" "R1692"
			(at 0 0 0)
			(layer "F.SilkS")
			(hide yes)
			(effects
				(font
					(size 1.27 1.27)
				)
			)
		)
		(property "Value" ""
			(at 0 0 0)
			(layer "F.Fab")
			(effects
				(font
					(size 1.27 1.27)
				)
			)
		)
		(duplicate_pad_numbers_are_jumpers no)
		(fp_line
			(start -0.7874 -0.4064)
			(end 0.7874 -0.4064)
			(stroke
				(width 0.1524)
				(type default)
			)
			(layer "F.SilkS")
		)
		(fp_line
			(start -0.7874 0.4064)
			(end -0.7874 -0.4064)
			(stroke
				(width 0.1524)
				(type default)
			)
			(layer "F.SilkS")
		)
		(fp_line
			(start 0.7874 -0.4064)
			(end 0.7874 0.4064)
			(stroke
				(width 0.1524)
				(type default)
			)
			(layer "F.SilkS")
		)
		(fp_line
			(start 0.7874 0.4064)
			(end -0.7874 0.4064)
			(stroke
				(width 0.1524)
				(type default)
			)
			(layer "F.SilkS")
		)
		(fp_line
			(start -0.67945 -0.305054)
			(end -0.12065 -0.305054)
			(stroke
				(width 0.1)
				(type default)
			)
			(layer "F.Fab")
		)
		(fp_line
			(start -0.67945 0.3048)
			(end -0.67945 -0.305054)
			(stroke
				(width 0.1)
				(type default)
			)
			(layer "F.Fab")
		)
		(fp_line
			(start -0.12065 -0.305054)
			(end -0.12065 -0.2794)
			(stroke
				(width 0.1)
				(type default)
			)
			(layer "F.Fab")
		)
		(fp_line
			(start -0.12065 -0.2794)
			(end 0.12065 -0.2794)
			(stroke
				(width 0.1)
				(type default)
			)
			(layer "F.Fab")
		)
		(fp_line
			(start -0.12065 0.2794)
			(end -0.12065 0.3048)
			(stroke
				(width 0.1)
				(type default)
			)
			(layer "F.Fab")
		)
		(fp_line
			(start -0.12065 0.3048)
			(end -0.67945 0.3048)
			(stroke
				(width 0.1)
				(type default)
			)
			(layer "F.Fab")
		)
		(fp_line
			(start 0.120396 0.2794)
			(end -0.12065 0.2794)
			(stroke
				(width 0.1)
				(type default)
			)
			(layer "F.Fab")
		)
		(fp_line
			(start 0.120396 0.3048)
			(end 0.120396 0.2794)
			(stroke
				(width 0.1)
				(type default)
			)
			(layer "F.Fab")
		)
		(fp_line
			(start 0.12065 -0.3048)
			(end 0.67945 -0.3048)
			(stroke
				(width 0.1)
				(type default)
			)
			(layer "F.Fab")
		)
		(fp_line
			(start 0.12065 -0.2794)
			(end 0.12065 -0.3048)
			(stroke
				(width 0.1)
				(type default)
			)
			(layer "F.Fab")
		)
		(fp_line
			(start 0.67945 -0.3048)
			(end 0.67945 0.3048)
			(stroke
				(width 0.1)
				(type default)
			)
			(layer "F.Fab")
		)
		(fp_line
			(start 0.67945 0.3048)
			(end 0.120396 0.3048)
			(stroke
				(width 0.1)
				(type default)
			)
			(layer "F.Fab")
		)
		(pad "1" smd circle
			(at -0.40005 0)
			(size 0 0)
			(layers "F.Cu" "F.Mask" "F.Paste")
			(net "PWRGD_DSW_PWROK_R1")
		)
		(pad "2" smd circle
			(at 0.40005 0)
			(size 0 0)
			(layers "F.Cu" "F.Mask" "F.Paste")
			(net "GND")
		)
	)
	(footprint ""
		(layer "F.Cu")
		(at 48.931068 -175.179482 180)
		(property "Reference" "PR1798"
			(at 0 0 180)
			(layer "F.SilkS")
			(hide yes)
			(effects
				(font
					(size 1.27 1.27)
				)
			)
		)
		(property "Value" ""
			(at 0 0 180)
			(layer "F.Fab")
			(effects
				(font
					(size 1.27 1.27)
				)
			)
		)
		(duplicate_pad_numbers_are_jumpers no)
		(fp_line
			(start 0.7874 0.4064)
			(end -0.7874 0.4064)
			(stroke
				(width 0.1524)
				(type default)
			)
			(layer "F.SilkS")
		)
		(fp_line
			(start 0.7874 -0.4064)
			(end 0.7874 0.4064)
			(stroke
				(width 0.1524)
				(type default)
			)
			(layer "F.SilkS")
		)
		(fp_line
			(start -0.7874 0.4064)
			(end -0.7874 -0.4064)
			(stroke
				(width 0.1524)
				(type default)
			)
			(layer "F.SilkS")
		)
		(fp_line
			(start -0.7874 -0.4064)
			(end 0.7874 -0.4064)
			(stroke
				(width 0.1524)
				(type default)
			)
			(layer "F.SilkS")
		)
		(fp_line
			(start 0.67945 0.3048)
			(end 0.120396 0.3048)
			(stroke
				(width 0.1)
				(type default)
			)
			(layer "F.Fab")
		)
		(fp_line
			(start 0.67945 -0.3048)
			(end 0.67945 0.3048)
			(stroke
				(width 0.1)
				(type default)
			)
			(layer "F.Fab")
		)
		(fp_line
			(start 0.12065 -0.2794)
			(end 0.12065 -0.3048)
			(stroke
				(width 0.1)
				(type default)
			)
			(layer "F.Fab")
		)
		(fp_line
			(start 0.12065 -0.3048)
			(end 0.67945 -0.3048)
			(stroke
				(width 0.1)
				(type default)
			)
			(layer "F.Fab")
		)
		(fp_line
			(start 0.120396 0.3048)
			(end 0.120396 0.2794)
			(stroke
				(width 0.1)
				(type default)
			)
			(layer "F.Fab")
		)
		(fp_line
			(start 0.120396 0.2794)
			(end -0.12065 0.2794)
			(stroke
				(width 0.1)
				(type default)
			)
			(layer "F.Fab")
		)
		(fp_line
			(start -0.12065 0.3048)
			(end -0.67945 0.3048)
			(stroke
				(width 0.1)
				(type default)
			)
			(layer "F.Fab")
		)
		(fp_line
			(start -0.12065 0.2794)
			(end -0.12065 0.3048)
			(stroke
				(width 0.1)
				(type default)
			)
			(layer "F.Fab")
		)
		(fp_line
			(start -0.12065 -0.2794)
			(end 0.12065 -0.2794)
			(stroke
				(width 0.1)
				(type default)
			)
			(layer "F.Fab")
		)
		(fp_line
			(start -0.12065 -0.305054)
			(end -0.12065 -0.2794)
			(stroke
				(width 0.1)
				(type default)
			)
			(layer "F.Fab")
		)
		(fp_line
			(start -0.67945 0.3048)
			(end -0.67945 -0.305054)
			(stroke
				(width 0.1)
				(type default)
			)
			(layer "F.Fab")
		)
		(fp_line
			(start -0.67945 -0.305054)
			(end -0.12065 -0.305054)
			(stroke
				(width 0.1)
				(type default)
			)
			(layer "F.Fab")
		)
		(pad "1" smd circle
			(at -0.40005 0 180)
			(size 0 0)
			(layers "F.Cu" "F.Mask" "F.Paste")
			(net "SW_PVCCFA_EHV_CPU1_BOOT1")
		)
		(pad "2" smd circle
			(at 0.40005 0 180)
			(size 0 0)
			(layers "F.Cu" "F.Mask" "F.Paste")
			(net "SW_PVCCFA_EHV_CPU1_BOOT1_R")
		)
	)
	(footprint ""
		(layer "F.Cu")
		(at 20.60956 -75.132692)
		(property "Reference" "R3135"
			(at 0 0 0)
			(layer "F.SilkS")
			(hide yes)
			(effects
				(font
					(size 1.27 1.27)
				)
			)
		)
		(property "Value" ""
			(at 0 0 0)
			(layer "F.Fab")
			(effects
				(font
					(size 1.27 1.27)
				)
			)
		)
		(duplicate_pad_numbers_are_jumpers no)
		(fp_line
			(start -0.7874 -0.4064)
			(end 0.7874 -0.4064)
			(stroke
				(width 0.1524)
				(type default)
			)
			(layer "F.SilkS")
		)
		(fp_line
			(start -0.7874 0.4064)
			(end -0.7874 -0.4064)
			(stroke
				(width 0.1524)
				(type default)
			)
			(layer "F.SilkS")
		)
		(fp_line
			(start 0.7874 -0.4064)
			(end 0.7874 0.4064)
			(stroke
				(width 0.1524)
				(type default)
			)
			(layer "F.SilkS")
		)
		(fp_line
			(start 0.7874 0.4064)
			(end -0.7874 0.4064)
			(stroke
				(width 0.1524)
				(type default)
			)
			(layer "F.SilkS")
		)
		(fp_line
			(start -0.67945 -0.305054)
			(end -0.12065 -0.305054)
			(stroke
				(width 0.1)
				(type default)
			)
			(layer "F.Fab")
		)
		(fp_line
			(start -0.67945 0.3048)
			(end -0.67945 -0.305054)
			(stroke
				(width 0.1)
				(type default)
			)
			(layer "F.Fab")
		)
		(fp_line
			(start -0.12065 -0.305054)
			(end -0.12065 -0.2794)
			(stroke
				(width 0.1)
				(type default)
			)
			(layer "F.Fab")
		)
		(fp_line
			(start -0.12065 -0.2794)
			(end 0.12065 -0.2794)
			(stroke
				(width 0.1)
				(type default)
			)
			(layer "F.Fab")
		)
		(fp_line
			(start -0.12065 0.2794)
			(end -0.12065 0.3048)
			(stroke
				(width 0.1)
				(type default)
			)
			(layer "F.Fab")
		)
		(fp_line
			(start -0.12065 0.3048)
			(end -0.67945 0.3048)
			(stroke
				(width 0.1)
				(type default)
			)
			(layer "F.Fab")
		)
		(fp_line
			(start 0.120396 0.2794)
			(end -0.12065 0.2794)
			(stroke
				(width 0.1)
				(type default)
			)
			(layer "F.Fab")
		)
		(fp_line
			(start 0.120396 0.3048)
			(end 0.120396 0.2794)
			(stroke
				(width 0.1)
				(type default)
			)
			(layer "F.Fab")
		)
		(fp_line
			(start 0.12065 -0.3048)
			(end 0.67945 -0.3048)
			(stroke
				(width 0.1)
				(type default)
			)
			(layer "F.Fab")
		)
		(fp_line
			(start 0.12065 -0.2794)
			(end 0.12065 -0.3048)
			(stroke
				(width 0.1)
				(type default)
			)
			(layer "F.Fab")
		)
		(fp_line
			(start 0.67945 -0.3048)
			(end 0.67945 0.3048)
			(stroke
				(width 0.1)
				(type default)
			)
			(layer "F.Fab")
		)
		(fp_line
			(start 0.67945 0.3048)
			(end 0.120396 0.3048)
			(stroke
				(width 0.1)
				(type default)
			)
			(layer "F.Fab")
		)
		(pad "1" smd circle
			(at -0.40005 0)
			(size 0 0)
			(layers "F.Cu" "F.Mask" "F.Paste")
			(net "P3V3_AUX")
		)
		(pad "2" smd circle
			(at 0.40005 0)
			(size 0 0)
			(layers "F.Cu" "F.Mask" "F.Paste")
			(net "OCP_V3_2_PRSNT1_R_N")
		)
	)
	(footprint ""
		(layer "F.Cu")
		(at 256.14503 -70.40626 -90)
		(property "Reference" "PC1217"
			(at 0 0 270)
			(layer "F.SilkS")
			(hide yes)
			(effects
				(font
					(size 1.27 1.27)
				)
			)
		)
		(property "Value" ""
			(at 0 0 270)
			(layer "F.Fab")
			(effects
				(font
					(size 1.27 1.27)
				)
			)
		)
		(duplicate_pad_numbers_are_jumpers no)
		(fp_line
			(start -1.524 0.762)
			(end -1.524 -0.762)
			(stroke
				(width 0.1524)
				(type default)
			)
			(layer "F.SilkS")
		)
		(fp_line
			(start 1.524 0.762)
			(end -1.524 0.762)
			(stroke
				(width 0.1524)
				(type default)
			)
			(layer "F.SilkS")
		)
		(fp_line
			(start -1.524 -0.762)
			(end 1.524 -0.762)
			(stroke
				(width 0.1524)
				(type default)
			)
			(layer "F.SilkS")
		)
		(fp_line
			(start 1.524 -0.762)
			(end 1.524 0.762)
			(stroke
				(width 0.1524)
				(type default)
			)
			(layer "F.SilkS")
		)
		(fp_line
			(start -1.1049 0.724916)
			(end 1.1049 0.724916)
			(stroke
				(width 0.1)
				(type default)
			)
			(layer "F.Fab")
		)
		(fp_line
			(start 1.1049 0.724916)
			(end 1.1049 -0.724916)
			(stroke
				(width 0.1)
				(type default)
			)
			(layer "F.Fab")
		)
		(fp_line
			(start -1.1049 -0.724916)
			(end -1.1049 0.724916)
			(stroke
				(width 0.1)
				(type default)
			)
			(layer "F.Fab")
		)
		(fp_line
			(start 1.1049 -0.724916)
			(end -1.1049 -0.724916)
			(stroke
				(width 0.1)
				(type default)
			)
			(layer "F.Fab")
		)
		(pad "1" smd rect
			(at -0.889 0 90)
			(size 1.016 1.27)
			(layers "F.Cu" "F.Mask" "F.Paste")
			(net "SW_P12V_AUX_P1V05_PCH_AUX_FLT")
		)
		(pad "2" smd rect
			(at 0.889 0 90)
			(size 1.016 1.27)
			(layers "F.Cu" "F.Mask" "F.Paste")
			(net "GND")
		)
	)
	(footprint ""
		(layer "F.Cu")
		(at 82.706718 -21.016722 90)
		(property "Reference" "R3816"
			(at 0 0 90)
			(layer "F.SilkS")
			(hide yes)
			(effects
				(font
					(size 1.27 1.27)
				)
			)
		)
		(property "Value" ""
			(at 0 0 90)
			(layer "F.Fab")
			(effects
				(font
					(size 1.27 1.27)
				)
			)
		)
		(duplicate_pad_numbers_are_jumpers no)
		(fp_line
			(start 0.7874 -0.4064)
			(end 0.7874 0.4064)
			(stroke
				(width 0.1524)
				(type default)
			)
			(layer "F.SilkS")
		)
		(fp_line
			(start -0.7874 -0.4064)
			(end 0.7874 -0.4064)
			(stroke
				(width 0.1524)
				(type default)
			)
			(layer "F.SilkS")
		)
		(fp_line
			(start 0.7874 0.4064)
			(end -0.7874 0.4064)
			(stroke
				(width 0.1524)
				(type default)
			)
			(layer "F.SilkS")
		)
		(fp_line
			(start -0.7874 0.4064)
			(end -0.7874 -0.4064)
			(stroke
				(width 0.1524)
				(type default)
			)
			(layer "F.SilkS")
		)
		(fp_line
			(start -0.12065 -0.305054)
			(end -0.12065 -0.2794)
			(stroke
				(width 0.1)
				(type default)
			)
			(layer "F.Fab")
		)
		(fp_line
			(start -0.67945 -0.305054)
			(end -0.12065 -0.305054)
			(stroke
				(width 0.1)
				(type default)
			)
			(layer "F.Fab")
		)
		(fp_line
			(start 0.67945 -0.3048)
			(end 0.67945 0.3048)
			(stroke
				(width 0.1)
				(type default)
			)
			(layer "F.Fab")
		)
		(fp_line
			(start 0.12065 -0.3048)
			(end 0.67945 -0.3048)
			(stroke
				(width 0.1)
				(type default)
			)
			(layer "F.Fab")
		)
		(fp_line
			(start 0.12065 -0.2794)
			(end 0.12065 -0.3048)
			(stroke
				(width 0.1)
				(type default)
			)
			(layer "F.Fab")
		)
		(fp_line
			(start -0.12065 -0.2794)
			(end 0.12065 -0.2794)
			(stroke
				(width 0.1)
				(type default)
			)
			(layer "F.Fab")
		)
		(fp_line
			(start 0.120396 0.2794)
			(end -0.12065 0.2794)
			(stroke
				(width 0.1)
				(type default)
			)
			(layer "F.Fab")
		)
		(fp_line
			(start -0.12065 0.2794)
			(end -0.12065 0.3048)
			(stroke
				(width 0.1)
				(type default)
			)
			(layer "F.Fab")
		)
		(fp_line
			(start 0.67945 0.3048)
			(end 0.120396 0.3048)
			(stroke
				(width 0.1)
				(type default)
			)
			(layer "F.Fab")
		)
		(fp_line
			(start 0.120396 0.3048)
			(end 0.120396 0.2794)
			(stroke
				(width 0.1)
				(type default)
			)
			(layer "F.Fab")
		)
		(fp_line
			(start -0.12065 0.3048)
			(end -0.67945 0.3048)
			(stroke
				(width 0.1)
				(type default)
			)
			(layer "F.Fab")
		)
		(fp_line
			(start -0.67945 0.3048)
			(end -0.67945 -0.305054)
			(stroke
				(width 0.1)
				(type default)
			)
			(layer "F.Fab")
		)
		(pad "1" smd circle
			(at -0.40005 0 90)
			(size 0 0)
			(layers "F.Cu" "F.Mask" "F.Paste")
			(net "P3V3_AUX")
		)
		(pad "2" smd circle
			(at 0.40005 0 90)
			(size 0 0)
			(layers "F.Cu" "F.Mask" "F.Paste")
			(net "P12V_OCP_FAULT_2")
		)
	)
	(footprint ""
		(layer "F.Cu")
		(at 415.101786 -346.010992)
		(property "Reference" "PC1185"
			(at 0 0 0)
			(layer "F.SilkS")
			(hide yes)
			(effects
				(font
					(size 1.27 1.27)
				)
			)
		)
		(property "Value" ""
			(at 0 0 0)
			(layer "F.Fab")
			(effects
				(font
					(size 1.27 1.27)
				)
			)
		)
		(duplicate_pad_numbers_are_jumpers no)
		(fp_line
			(start 2.750058 0.999998)
			(end -2.750058 0.999998)
			(stroke
				(width 0.1524)
				(type default)
			)
			(layer "F.SilkS")
		)
		(fp_circle
			(center 0 0.999998)
			(end 2.750058 0.999998)
			(stroke
				(width 0.1524)
				(type default)
			)
			(fill no)
			(layer "F.SilkS")
		)
		(fp_poly
			(pts
				(arc
					(start 2.750058 0.999998)
					(mid 0 3.750056)
					(end -2.750058 0.999998)
				)
			)
			(stroke
				(width 0)
				(type default)
			)
			(fill yes)
			(layer "F.SilkS")
		)
		(fp_circle
			(center 0 0.999998)
			(end 2.750058 0.999998)
			(stroke
				(width 0.1)
				(type default)
			)
			(fill no)
			(layer "F.Fab")
		)
		(pad "1" thru_hole rect
			(at 0 0)
			(size 1.5748 1.5748)
			(drill 1.0668)
			(layers "*.Cu" "*.Mask")
			(remove_unused_layers no)
			(net "PVCCFA_EHV_FIVRA_CPU0")
			(clearance 0)
			(padstack
				(mode front_inner_back)
				(layer "Inner"
					(shape circle)
					(size 1.5748 1.5748)
					(clearance 0)
				)
				(layer "B.Cu"
					(shape rect)
					(size 1.5748 1.5748)
					(clearance 0)
				)
			)
		)
		(pad "2" thru_hole circle
			(at 0 1.999996)
			(size 1.5748 1.5748)
			(drill 1.0668)
			(layers "*.Cu" "*.Mask")
			(remove_unused_layers no)
			(net "GND")
			(clearance 0)
		)
	)
)
